# T6G (Grand Teton) — schematic netlist excerpt (pin names and nets, part order shuffled) for the footprints in the layout excerpt that follows; sources: Cadence DE-HDL packaged netlist, KiCad conversion of 04192023_DAF0TMB3IC0_F0TG_MB_C_brd_V02_OCP.brd

PR6011  Q_RES  10K 1% CHIP  pkg 0402LF  page 270 : A = P1V2_AUX_FB ; B = GND
R9034  Q_RES  33.2 1% CHIP  pkg 0402LF  page 136 : A = OCP_V3_1_P3V3_R3_PWRGD ; B = HP_LVC3_OCP_V3_1_PWRGD_R1

(kicad_pcb
	(version 20260206)
	(generator "pcbnew")
	(generator_version "10.0")
	(general
		(thickness 1.6)
		(legacy_teardrops no)
	)
	(paper "A4")
	(title_block
		(title "04192023_DAF0TMB3IC0_F0TG_MB_C_brd_V02_OCP.brd")
		(comment 1 "Grand Teton / footprints 929-930 of 8354")
	)
	(layers
		(0 "F.Cu" signal "TOP")
		(4 "In1.Cu" signal "GND")
		(6 "In2.Cu" signal "IN1")
		(8 "In3.Cu" signal "GND1")
		(10 "In4.Cu" signal "IN2")
		(12 "In5.Cu" signal "GND2")
		(14 "In6.Cu" signal "IN3")
		(16 "In7.Cu" signal "GND3")
		(18 "In8.Cu" signal "VCC")
		(20 "In9.Cu" signal "VCC1")
		(22 "In10.Cu" signal "GND4")
		(24 "In11.Cu" signal "IN4")
		(26 "In12.Cu" signal "GND5")
		(28 "In13.Cu" signal "IN5")
		(30 "In14.Cu" signal "GND6")
		(32 "In15.Cu" signal "IN6")
		(34 "In16.Cu" signal "GND7")
		(2 "B.Cu" signal "BOTTOM")
		(9 "F.Adhes" user "F.Adhesive")
		(11 "B.Adhes" user "B.Adhesive")
		(13 "F.Paste" user "Package Geometry/Pastemask Top")
		(15 "B.Paste" user "Package Geometry/Pastemask Bottom")
		(5 "F.SilkS" user "Ref Des/Silkscreen Top")
		(7 "B.SilkS" user "Ref Des/Silkscreen Bottom")
		(1 "F.Mask" user "Board Geometry/Soldermask Top")
		(3 "B.Mask" user "Board Geometry/Soldermask Bottom")
		(17 "Dwgs.User" user "User.Drawings")
		(19 "Cmts.User" user "User.Comments")
		(21 "Eco1.User" user "User.Eco1")
		(23 "Eco2.User" user "User.Eco2")
		(25 "Edge.Cuts" user "Board Geometry/Outline")
		(27 "Margin" user)
		(31 "F.CrtYd" user "Package Geometry/Place Bound Top")
		(29 "B.CrtYd" user "Package Geometry/Place Bound Bottom")
		(35 "F.Fab" user "Ref Des/Assembly Top")
		(33 "B.Fab" user "Ref Des/Assembly Bottom")
	)
	(footprint ""
		(layer "F.Cu")
		(at 120.631712 -73.296272 -0.054)
		(property "Reference" "PR6011"
			(at 0 0 359.946)
			(layer "F.SilkS")
			(hide yes)
			(effects
				(font
					(size 1.27 1.27)
				)
			)
		)
		(property "Value" ""
			(at 0 0 359.946)
			(layer "F.Fab")
			(effects
				(font
					(size 1.27 1.27)
				)
			)
		)
		(duplicate_pad_numbers_are_jumpers no)
		(fp_line
			(start -0.787525 0.40638)
			(end -0.787275 -0.40642)
			(stroke
				(width 0.1524)
				(type default)
			)
			(layer "F.SilkS")
		)
		(fp_line
			(start -0.787275 -0.40642)
			(end 0.787525 -0.40638)
			(stroke
				(width 0.1524)
				(type default)
			)
			(layer "F.SilkS")
		)
		(fp_line
			(start 0.787275 0.40642)
			(end -0.787525 0.40638)
			(stroke
				(width 0.1524)
				(type default)
			)
			(layer "F.SilkS")
		)
		(fp_line
			(start 0.787525 -0.40638)
			(end 0.787275 0.40642)
			(stroke
				(width 0.1524)
				(type default)
			)
			(layer "F.SilkS")
		)
		(fp_line
			(start -0.679417 0.304678)
			(end -0.679484 -0.305176)
			(stroke
				(width 0.1)
				(type default)
			)
			(layer "F.Fab")
		)
		(fp_line
			(start -0.679484 -0.305176)
			(end -0.120683 -0.30494)
			(stroke
				(width 0.1)
				(type default)
			)
			(layer "F.Fab")
		)
		(fp_line
			(start -0.120641 0.279514)
			(end -0.120617 0.304914)
			(stroke
				(width 0.1)
				(type default)
			)
			(layer "F.Fab")
		)
		(fp_line
			(start -0.120617 0.304914)
			(end -0.679417 0.304678)
			(stroke
				(width 0.1)
				(type default)
			)
			(layer "F.Fab")
		)
		(fp_line
			(start -0.120683 -0.30494)
			(end -0.120659 -0.279286)
			(stroke
				(width 0.1)
				(type default)
			)
			(layer "F.Fab")
		)
		(fp_line
			(start -0.120659 -0.279286)
			(end 0.120641 -0.279514)
			(stroke
				(width 0.1)
				(type default)
			)
			(layer "F.Fab")
		)
		(fp_line
			(start 0.120405 0.279287)
			(end -0.120641 0.279514)
			(stroke
				(width 0.1)
				(type default)
			)
			(layer "F.Fab")
		)
		(fp_line
			(start 0.120429 0.304687)
			(end 0.120405 0.279287)
			(stroke
				(width 0.1)
				(type default)
			)
			(layer "F.Fab")
		)
		(fp_line
			(start 0.120617 -0.304914)
			(end 0.679417 -0.304678)
			(stroke
				(width 0.1)
				(type default)
			)
			(layer "F.Fab")
		)
		(fp_line
			(start 0.120641 -0.279514)
			(end 0.120617 -0.304914)
			(stroke
				(width 0.1)
				(type default)
			)
			(layer "F.Fab")
		)
		(fp_line
			(start 0.679484 0.304922)
			(end 0.120429 0.304687)
			(stroke
				(width 0.1)
				(type default)
			)
			(layer "F.Fab")
		)
		(fp_line
			(start 0.679417 -0.304678)
			(end 0.679484 0.304922)
			(stroke
				(width 0.1)
				(type default)
			)
			(layer "F.Fab")
		)
		(pad "1" smd circle
			(at -0.40005 0 359.946)
			(size 0 0)
			(layers "F.Cu" "F.Mask" "F.Paste")
			(net "P1V2_AUX_FB")
		)
		(pad "2" smd circle
			(at 0.40005 0 359.946)
			(size 0 0)
			(layers "F.Cu" "F.Mask" "F.Paste")
			(net "GND")
		)
	)
	(footprint ""
		(layer "F.Cu")
		(at 218.567 -99.441 180)
		(property "Reference" "R9034"
			(at 0 0 180)
			(layer "F.SilkS")
			(hide yes)
			(effects
				(font
					(size 1.27 1.27)
				)
			)
		)
		(property "Value" ""
			(at 0 0 180)
			(layer "F.Fab")
			(effects
				(font
					(size 1.27 1.27)
				)
			)
		)
		(duplicate_pad_numbers_are_jumpers no)
		(fp_line
			(start 0.7874 0.4064)
			(end -0.7874 0.4064)
			(stroke
				(width 0.1524)
				(type default)
			)
			(layer "F.SilkS")
		)
		(fp_line
			(start 0.7874 -0.4064)
			(end 0.7874 0.4064)
			(stroke
				(width 0.1524)
				(type default)
			)
			(layer "F.SilkS")
		)
		(fp_line
			(start -0.7874 0.4064)
			(end -0.7874 -0.4064)
			(stroke
				(width 0.1524)
				(type default)
			)
			(layer "F.SilkS")
		)
		(fp_line
			(start -0.7874 -0.4064)
			(end 0.7874 -0.4064)
			(stroke
				(width 0.1524)
				(type default)
			)
			(layer "F.SilkS")
		)
		(fp_line
			(start 0.67945 0.3048)
			(end 0.120396 0.3048)
			(stroke
				(width 0.1)
				(type default)
			)
			(layer "F.Fab")
		)
		(fp_line
			(start 0.67945 -0.3048)
			(end 0.67945 0.3048)
			(stroke
				(width 0.1)
				(type default)
			)
			(layer "F.Fab")
		)
		(fp_line
			(start 0.12065 -0.2794)
			(end 0.12065 -0.3048)
			(stroke
				(width 0.1)
				(type default)
			)
			(layer "F.Fab")
		)
		(fp_line
			(start 0.12065 -0.3048)
			(end 0.67945 -0.3048)
			(stroke
				(width 0.1)
				(type default)
			)
			(layer "F.Fab")
		)
		(fp_line
			(start 0.120396 0.3048)
			(end 0.120396 0.2794)
			(stroke
				(width 0.1)
				(type default)
			)
			(layer "F.Fab")
		)
		(fp_line
			(start 0.120396 0.2794)
			(end -0.12065 0.2794)
			(stroke
				(width 0.1)
				(type default)
			)
			(layer "F.Fab")
		)
		(fp_line
			(start -0.12065 0.3048)
			(end -0.67945 0.3048)
			(stroke
				(width 0.1)
				(type default)
			)
			(layer "F.Fab")
		)
		(fp_line
			(start -0.12065 0.2794)
			(end -0.12065 0.3048)
			(stroke
				(width 0.1)
				(type default)
			)
			(layer "F.Fab")
		)
		(fp_line
			(start -0.12065 -0.2794)
			(end 0.12065 -0.2794)
			(stroke
				(width 0.1)
				(type default)
			)
			(layer "F.Fab")
		)
		(fp_line
			(start -0.12065 -0.305054)
			(end -0.12065 -0.2794)
			(stroke
				(width 0.1)
				(type default)
			)
			(layer "F.Fab")
		)
		(fp_line
			(start -0.67945 0.3048)
			(end -0.67945 -0.305054)
			(stroke
				(width 0.1)
				(type default)
			)
			(layer "F.Fab")
		)
		(fp_line
			(start -0.67945 -0.305054)
			(end -0.12065 -0.305054)
			(stroke
				(width 0.1)
				(type default)
			)
			(layer "F.Fab")
		)
		(pad "1" smd circle
			(at -0.40005 0 180)
			(size 0 0)
			(layers "F.Cu" "F.Mask" "F.Paste")
			(net "OCP_V3_1_P3V3_R3_PWRGD")
		)
		(pad "2" smd circle
			(at 0.40005 0 180)
			(size 0 0)
			(layers "F.Cu" "F.Mask" "F.Paste")
			(net "HP_LVC3_OCP_V3_1_PWRGD_R1")
		)
	)
)
